(kicad_pcb
	(version 20260206)
	(generator "pcbnew")
	(generator_version "10.0")
	(general
		(thickness 1.6)
		(legacy_teardrops no)
	)
	(paper "A4")
	(title_block
		(title "01162023_DA0F0TEBIF0_F0T_Expander_BD_F_brd_V02_OCP.brd")
		(comment 1 "Grand Teton / footprints 395-401 of 9728")
	)
	(layers
		(0 "F.Cu" signal "TOP")
		(4 "In1.Cu" signal "GND")
		(6 "In2.Cu" signal "VCC")
		(8 "In3.Cu" signal "VCC1")
		(10 "In4.Cu" signal "GND1")
		(12 "In5.Cu" signal "IN1")
		(14 "In6.Cu" signal "GND2")
		(16 "In7.Cu" signal "IN2")
		(18 "In8.Cu" signal "GND3")
		(20 "In9.Cu" signal "IN3")
		(22 "In10.Cu" signal "GND4")
		(24 "In11.Cu" signal "IN4")
		(26 "In12.Cu" signal "GND5")
		(28 "In13.Cu" signal "IN5")
		(30 "In14.Cu" signal "GND6")
		(32 "In15.Cu" signal "IN6")
		(34 "In16.Cu" signal "GND7")
		(2 "B.Cu" signal "BOTTOM")
		(9 "F.Adhes" user "F.Adhesive")
		(11 "B.Adhes" user "B.Adhesive")
		(13 "F.Paste" user "Package Geometry/Pastemask Top")
		(15 "B.Paste" user "Package Geometry/Pastemask Bottom")
		(5 "F.SilkS" user "Ref Des/Silkscreen Top")
		(7 "B.SilkS" user "Ref Des/Silkscreen Bottom")
		(1 "F.Mask" user "Board Geometry/Soldermask Top")
		(3 "B.Mask" user "Board Geometry/Soldermask Bottom")
		(17 "Dwgs.User" user "User.Drawings")
		(19 "Cmts.User" user "User.Comments")
		(21 "Eco1.User" user "User.Eco1")
		(23 "Eco2.User" user "User.Eco2")
		(25 "Edge.Cuts" user "Board Geometry/Outline")
		(27 "Margin" user)
		(31 "F.CrtYd" user "Package Geometry/Place Bound Top")
		(29 "B.CrtYd" user "Package Geometry/Place Bound Bottom")
		(35 "F.Fab" user "Ref Des/Assembly Top")
		(33 "B.Fab" user "Ref Des/Assembly Bottom")
	)
	(footprint ""
		(layer "F.Cu")
		(at 38.79088 -142.892018)
		(property "Reference" "R30"
			(at 0 0 0)
			(layer "F.SilkS")
			(hide yes)
			(effects
				(font
					(size 1.27 1.27)
				)
			)
		)
		(property "Value" ""
			(at 0 0 0)
			(layer "F.Fab")
			(effects
				(font
					(size 1.27 1.27)
				)
			)
		)
		(duplicate_pad_numbers_are_jumpers no)
		(fp_line
			(start -0.7874 -0.4064)
			(end 0.7874 -0.4064)
			(stroke
				(width 0.1524)
				(type default)
			)
			(layer "F.SilkS")
		)
		(fp_line
			(start -0.7874 0.4064)
			(end -0.7874 -0.4064)
			(stroke
				(width 0.1524)
				(type default)
			)
			(layer "F.SilkS")
		)
		(fp_line
			(start 0.7874 -0.4064)
			(end 0.7874 0.4064)
			(stroke
				(width 0.1524)
				(type default)
			)
			(layer "F.SilkS")
		)
		(fp_line
			(start 0.7874 0.4064)
			(end -0.7874 0.4064)
			(stroke
				(width 0.1524)
				(type default)
			)
			(layer "F.SilkS")
		)
		(fp_line
			(start -0.67945 -0.305054)
			(end -0.12065 -0.305054)
			(stroke
				(width 0.1)
				(type default)
			)
			(layer "F.Fab")
		)
		(fp_line
			(start -0.67945 0.3048)
			(end -0.67945 -0.305054)
			(stroke
				(width 0.1)
				(type default)
			)
			(layer "F.Fab")
		)
		(fp_line
			(start -0.12065 -0.305054)
			(end -0.12065 -0.2794)
			(stroke
				(width 0.1)
				(type default)
			)
			(layer "F.Fab")
		)
		(fp_line
			(start -0.12065 -0.2794)
			(end 0.12065 -0.2794)
			(stroke
				(width 0.1)
				(type default)
			)
			(layer "F.Fab")
		)
		(fp_line
			(start -0.12065 0.2794)
			(end -0.12065 0.3048)
			(stroke
				(width 0.1)
				(type default)
			)
			(layer "F.Fab")
		)
		(fp_line
			(start -0.12065 0.3048)
			(end -0.67945 0.3048)
			(stroke
				(width 0.1)
				(type default)
			)
			(layer "F.Fab")
		)
		(fp_line
			(start 0.120396 0.2794)
			(end -0.12065 0.2794)
			(stroke
				(width 0.1)
				(type default)
			)
			(layer "F.Fab")
		)
		(fp_line
			(start 0.120396 0.3048)
			(end 0.120396 0.2794)
			(stroke
				(width 0.1)
				(type default)
			)
			(layer "F.Fab")
		)
		(fp_line
			(start 0.12065 -0.3048)
			(end 0.67945 -0.3048)
			(stroke
				(width 0.1)
				(type default)
			)
			(layer "F.Fab")
		)
		(fp_line
			(start 0.12065 -0.2794)
			(end 0.12065 -0.3048)
			(stroke
				(width 0.1)
				(type default)
			)
			(layer "F.Fab")
		)
		(fp_line
			(start 0.67945 -0.3048)
			(end 0.67945 0.3048)
			(stroke
				(width 0.1)
				(type default)
			)
			(layer "F.Fab")
		)
		(fp_line
			(start 0.67945 0.3048)
			(end 0.120396 0.3048)
			(stroke
				(width 0.1)
				(type default)
			)
			(layer "F.Fab")
		)
		(pad "1" smd circle
			(at -0.40005 0)
			(size 0 0)
			(layers "F.Cu" "F.Mask" "F.Paste")
			(net "NIC0_BIF0_N")
		)
		(pad "2" smd circle
			(at 0.40005 0)
			(size 0 0)
			(layers "F.Cu" "F.Mask" "F.Paste")
			(net "GND")
		)
	)
	(footprint ""
		(layer "F.Cu")
		(at 298.961302 -343.952322 90)
		(property "Reference" "C2369"
			(at 0 0 90)
			(layer "F.SilkS")
			(hide yes)
			(effects
				(font
					(size 1.27 1.27)
				)
			)
		)
		(property "Value" ""
			(at 0 0 90)
			(layer "F.Fab")
			(effects
				(font
					(size 1.27 1.27)
				)
			)
		)
		(duplicate_pad_numbers_are_jumpers no)
		(fp_line
			(start 0.299974 -0.150114)
			(end 0.299974 0.150114)
			(stroke
				(width 0.1)
				(type default)
			)
			(layer "F.Fab")
		)
		(fp_line
			(start -0.299974 -0.150114)
			(end 0.299974 -0.150114)
			(stroke
				(width 0.1)
				(type default)
			)
			(layer "F.Fab")
		)
		(fp_line
			(start 0.299974 0.150114)
			(end -0.299974 0.150114)
			(stroke
				(width 0.1)
				(type default)
			)
			(layer "F.Fab")
		)
		(fp_line
			(start -0.299974 0.150114)
			(end -0.299974 -0.150114)
			(stroke
				(width 0.1)
				(type default)
			)
			(layer "F.Fab")
		)
		(pad "1" smd rect
			(at -0.2667 0 90)
			(size 0.3048 0.381)
			(layers "F.Cu" "F.Mask" "F.Paste")
			(net "P5E_PEX2_STN4_TX_DP<65>")
		)
		(pad "2" smd rect
			(at 0.2667 0 90)
			(size 0.3048 0.381)
			(layers "F.Cu" "F.Mask" "F.Paste")
			(net "P5E_PEX2_STN4_TX_C_DP<65>")
		)
	)
	(footprint ""
		(layer "F.Cu")
		(at 92.387166 -300.650402 -90)
		(property "Reference" "R3884"
			(at 0 0 270)
			(layer "F.SilkS")
			(hide yes)
			(effects
				(font
					(size 1.27 1.27)
				)
			)
		)
		(property "Value" ""
			(at 0 0 270)
			(layer "F.Fab")
			(effects
				(font
					(size 1.27 1.27)
				)
			)
		)
		(duplicate_pad_numbers_are_jumpers no)
		(fp_line
			(start -0.7874 0.4064)
			(end -0.7874 -0.4064)
			(stroke
				(width 0.1524)
				(type default)
			)
			(layer "F.SilkS")
		)
		(fp_line
			(start 0.7874 0.4064)
			(end -0.7874 0.4064)
			(stroke
				(width 0.1524)
				(type default)
			)
			(layer "F.SilkS")
		)
		(fp_line
			(start -0.7874 -0.4064)
			(end 0.7874 -0.4064)
			(stroke
				(width 0.1524)
				(type default)
			)
			(layer "F.SilkS")
		)
		(fp_line
			(start 0.7874 -0.4064)
			(end 0.7874 0.4064)
			(stroke
				(width 0.1524)
				(type default)
			)
			(layer "F.SilkS")
		)
		(fp_line
			(start -0.67945 0.3048)
			(end -0.67945 -0.305054)
			(stroke
				(width 0.1)
				(type default)
			)
			(layer "F.Fab")
		)
		(fp_line
			(start -0.12065 0.3048)
			(end -0.67945 0.3048)
			(stroke
				(width 0.1)
				(type default)
			)
			(layer "F.Fab")
		)
		(fp_line
			(start 0.120396 0.3048)
			(end 0.120396 0.2794)
			(stroke
				(width 0.1)
				(type default)
			)
			(layer "F.Fab")
		)
		(fp_line
			(start 0.67945 0.3048)
			(end 0.120396 0.3048)
			(stroke
				(width 0.1)
				(type default)
			)
			(layer "F.Fab")
		)
		(fp_line
			(start -0.12065 0.2794)
			(end -0.12065 0.3048)
			(stroke
				(width 0.1)
				(type default)
			)
			(layer "F.Fab")
		)
		(fp_line
			(start 0.120396 0.2794)
			(end -0.12065 0.2794)
			(stroke
				(width 0.1)
				(type default)
			)
			(layer "F.Fab")
		)
		(fp_line
			(start -0.12065 -0.2794)
			(end 0.12065 -0.2794)
			(stroke
				(width 0.1)
				(type default)
			)
			(layer "F.Fab")
		)
		(fp_line
			(start 0.12065 -0.2794)
			(end 0.12065 -0.3048)
			(stroke
				(width 0.1)
				(type default)
			)
			(layer "F.Fab")
		)
		(fp_line
			(start 0.12065 -0.3048)
			(end 0.67945 -0.3048)
			(stroke
				(width 0.1)
				(type default)
			)
			(layer "F.Fab")
		)
		(fp_line
			(start 0.67945 -0.3048)
			(end 0.67945 0.3048)
			(stroke
				(width 0.1)
				(type default)
			)
			(layer "F.Fab")
		)
		(fp_line
			(start -0.67945 -0.305054)
			(end -0.12065 -0.305054)
			(stroke
				(width 0.1)
				(type default)
			)
			(layer "F.Fab")
		)
		(fp_line
			(start -0.12065 -0.305054)
			(end -0.12065 -0.2794)
			(stroke
				(width 0.1)
				(type default)
			)
			(layer "F.Fab")
		)
		(pad "1" smd circle
			(at -0.40005 0 270)
			(size 0 0)
			(layers "F.Cu" "F.Mask" "F.Paste")
			(net "I2C0_PEX0_SHPC_SCL")
		)
		(pad "2" smd circle
			(at 0.40005 0 270)
			(size 0 0)
			(layers "F.Cu" "F.Mask" "F.Paste")
			(net "I2C_PEX0_HOST_SCL")
		)
	)
	(footprint ""
		(layer "F.Cu")
		(at 174.164244 -140.6398 180)
		(property "Reference" "R140"
			(at 0 0 180)
			(layer "F.SilkS")
			(hide yes)
			(effects
				(font
					(size 1.27 1.27)
				)
			)
		)
		(property "Value" ""
			(at 0 0 180)
			(layer "F.Fab")
			(effects
				(font
					(size 1.27 1.27)
				)
			)
		)
		(duplicate_pad_numbers_are_jumpers no)
		(fp_line
			(start 0.7874 0.4064)
			(end -0.7874 0.4064)
			(stroke
				(width 0.1524)
				(type default)
			)
			(layer "F.SilkS")
		)
		(fp_line
			(start 0.7874 -0.4064)
			(end 0.7874 0.4064)
			(stroke
				(width 0.1524)
				(type default)
			)
			(layer "F.SilkS")
		)
		(fp_line
			(start -0.7874 0.4064)
			(end -0.7874 -0.4064)
			(stroke
				(width 0.1524)
				(type default)
			)
			(layer "F.SilkS")
		)
		(fp_line
			(start -0.7874 -0.4064)
			(end 0.7874 -0.4064)
			(stroke
				(width 0.1524)
				(type default)
			)
			(layer "F.SilkS")
		)
		(fp_line
			(start 0.67945 0.3048)
			(end 0.120396 0.3048)
			(stroke
				(width 0.1)
				(type default)
			)
			(layer "F.Fab")
		)
		(fp_line
			(start 0.67945 -0.3048)
			(end 0.67945 0.3048)
			(stroke
				(width 0.1)
				(type default)
			)
			(layer "F.Fab")
		)
		(fp_line
			(start 0.12065 -0.2794)
			(end 0.12065 -0.3048)
			(stroke
				(width 0.1)
				(type default)
			)
			(layer "F.Fab")
		)
		(fp_line
			(start 0.12065 -0.3048)
			(end 0.67945 -0.3048)
			(stroke
				(width 0.1)
				(type default)
			)
			(layer "F.Fab")
		)
		(fp_line
			(start 0.120396 0.3048)
			(end 0.120396 0.2794)
			(stroke
				(width 0.1)
				(type default)
			)
			(layer "F.Fab")
		)
		(fp_line
			(start 0.120396 0.2794)
			(end -0.12065 0.2794)
			(stroke
				(width 0.1)
				(type default)
			)
			(layer "F.Fab")
		)
		(fp_line
			(start -0.12065 0.3048)
			(end -0.67945 0.3048)
			(stroke
				(width 0.1)
				(type default)
			)
			(layer "F.Fab")
		)
		(fp_line
			(start -0.12065 0.2794)
			(end -0.12065 0.3048)
			(stroke
				(width 0.1)
				(type default)
			)
			(layer "F.Fab")
		)
		(fp_line
			(start -0.12065 -0.2794)
			(end 0.12065 -0.2794)
			(stroke
				(width 0.1)
				(type default)
			)
			(layer "F.Fab")
		)
		(fp_line
			(start -0.12065 -0.305054)
			(end -0.12065 -0.2794)
			(stroke
				(width 0.1)
				(type default)
			)
			(layer "F.Fab")
		)
		(fp_line
			(start -0.67945 0.3048)
			(end -0.67945 -0.305054)
			(stroke
				(width 0.1)
				(type default)
			)
			(layer "F.Fab")
		)
		(fp_line
			(start -0.67945 -0.305054)
			(end -0.12065 -0.305054)
			(stroke
				(width 0.1)
				(type default)
			)
			(layer "F.Fab")
		)
		(pad "1" smd circle
			(at -0.40005 0 180)
			(size 0 0)
			(layers "F.Cu" "F.Mask" "F.Paste")
			(net "RST_SMB_NIC2_MUX_ISO_N")
		)
		(pad "2" smd circle
			(at 0.40005 0 180)
			(size 0 0)
			(layers "F.Cu" "F.Mask" "F.Paste")
			(net "GND")
		)
	)
	(footprint ""
		(layer "F.Cu")
		(at 51.062382 -22.955504 -90)
		(property "Reference" "C2713"
			(at 0 0 270)
			(layer "F.SilkS")
			(hide yes)
			(effects
				(font
					(size 1.27 1.27)
				)
			)
		)
		(property "Value" ""
			(at 0 0 270)
			(layer "F.Fab")
			(effects
				(font
					(size 1.27 1.27)
				)
			)
		)
		(duplicate_pad_numbers_are_jumpers no)
		(fp_line
			(start -0.7874 0.4064)
			(end -0.7874 -0.4064)
			(stroke
				(width 0.1524)
				(type default)
			)
			(layer "F.SilkS")
		)
		(fp_line
			(start 0.7874 0.4064)
			(end -0.7874 0.4064)
			(stroke
				(width 0.1524)
				(type default)
			)
			(layer "F.SilkS")
		)
		(fp_line
			(start -0.7874 -0.4064)
			(end 0.7874 -0.4064)
			(stroke
				(width 0.1524)
				(type default)
			)
			(layer "F.SilkS")
		)
		(fp_line
			(start 0.7874 -0.4064)
			(end 0.7874 0.4064)
			(stroke
				(width 0.1524)
				(type default)
			)
			(layer "F.SilkS")
		)
		(fp_line
			(start -0.67945 0.3048)
			(end -0.67945 -0.305054)
			(stroke
				(width 0.1)
				(type default)
			)
			(layer "F.Fab")
		)
		(fp_line
			(start -0.12065 0.3048)
			(end -0.67945 0.3048)
			(stroke
				(width 0.1)
				(type default)
			)
			(layer "F.Fab")
		)
		(fp_line
			(start 0.120396 0.3048)
			(end 0.120396 0.2794)
			(stroke
				(width 0.1)
				(type default)
			)
			(layer "F.Fab")
		)
		(fp_line
			(start 0.67945 0.3048)
			(end 0.120396 0.3048)
			(stroke
				(width 0.1)
				(type default)
			)
			(layer "F.Fab")
		)
		(fp_line
			(start -0.12065 0.2794)
			(end -0.12065 0.3048)
			(stroke
				(width 0.1)
				(type default)
			)
			(layer "F.Fab")
		)
		(fp_line
			(start 0.120396 0.2794)
			(end -0.12065 0.2794)
			(stroke
				(width 0.1)
				(type default)
			)
			(layer "F.Fab")
		)
		(fp_line
			(start -0.12065 -0.2794)
			(end 0.12065 -0.2794)
			(stroke
				(width 0.1)
				(type default)
			)
			(layer "F.Fab")
		)
		(fp_line
			(start 0.12065 -0.2794)
			(end 0.12065 -0.3048)
			(stroke
				(width 0.1)
				(type default)
			)
			(layer "F.Fab")
		)
		(fp_line
			(start 0.12065 -0.3048)
			(end 0.67945 -0.3048)
			(stroke
				(width 0.1)
				(type default)
			)
			(layer "F.Fab")
		)
		(fp_line
			(start 0.67945 -0.3048)
			(end 0.67945 0.3048)
			(stroke
				(width 0.1)
				(type default)
			)
			(layer "F.Fab")
		)
		(fp_line
			(start -0.67945 -0.305054)
			(end -0.12065 -0.305054)
			(stroke
				(width 0.1)
				(type default)
			)
			(layer "F.Fab")
		)
		(fp_line
			(start -0.12065 -0.305054)
			(end -0.12065 -0.2794)
			(stroke
				(width 0.1)
				(type default)
			)
			(layer "F.Fab")
		)
		(pad "1" smd circle
			(at -0.40005 0 270)
			(size 0 0)
			(layers "F.Cu" "F.Mask" "F.Paste")
			(net "GND")
		)
		(pad "2" smd circle
			(at 0.40005 0 270)
			(size 0 0)
			(layers "F.Cu" "F.Mask" "F.Paste")
			(net "P3V3_AUX")
		)
	)
	(footprint ""
		(layer "F.Cu")
		(at 211.958936 -188.652404 90)
		(property "Reference" "R5416"
			(at 0 0 90)
			(layer "F.SilkS")
			(hide yes)
			(effects
				(font
					(size 1.27 1.27)
				)
			)
		)
		(property "Value" ""
			(at 0 0 90)
			(layer "F.Fab")
			(effects
				(font
					(size 1.27 1.27)
				)
			)
		)
		(duplicate_pad_numbers_are_jumpers no)
		(fp_line
			(start 0.7874 -0.4064)
			(end 0.7874 0.4064)
			(stroke
				(width 0.1524)
				(type default)
			)
			(layer "F.SilkS")
		)
		(fp_line
			(start -0.7874 -0.4064)
			(end 0.7874 -0.4064)
			(stroke
				(width 0.1524)
				(type default)
			)
			(layer "F.SilkS")
		)
		(fp_line
			(start 0.7874 0.4064)
			(end -0.7874 0.4064)
			(stroke
				(width 0.1524)
				(type default)
			)
			(layer "F.SilkS")
		)
		(fp_line
			(start -0.7874 0.4064)
			(end -0.7874 -0.4064)
			(stroke
				(width 0.1524)
				(type default)
			)
			(layer "F.SilkS")
		)
		(fp_line
			(start -0.12065 -0.305054)
			(end -0.12065 -0.2794)
			(stroke
				(width 0.1)
				(type default)
			)
			(layer "F.Fab")
		)
		(fp_line
			(start -0.67945 -0.305054)
			(end -0.12065 -0.305054)
			(stroke
				(width 0.1)
				(type default)
			)
			(layer "F.Fab")
		)
		(fp_line
			(start 0.67945 -0.3048)
			(end 0.67945 0.3048)
			(stroke
				(width 0.1)
				(type default)
			)
			(layer "F.Fab")
		)
		(fp_line
			(start 0.12065 -0.3048)
			(end 0.67945 -0.3048)
			(stroke
				(width 0.1)
				(type default)
			)
			(layer "F.Fab")
		)
		(fp_line
			(start 0.12065 -0.2794)
			(end 0.12065 -0.3048)
			(stroke
				(width 0.1)
				(type default)
			)
			(layer "F.Fab")
		)
		(fp_line
			(start -0.12065 -0.2794)
			(end 0.12065 -0.2794)
			(stroke
				(width 0.1)
				(type default)
			)
			(layer "F.Fab")
		)
		(fp_line
			(start 0.120396 0.2794)
			(end -0.12065 0.2794)
			(stroke
				(width 0.1)
				(type default)
			)
			(layer "F.Fab")
		)
		(fp_line
			(start -0.12065 0.2794)
			(end -0.12065 0.3048)
			(stroke
				(width 0.1)
				(type default)
			)
			(layer "F.Fab")
		)
		(fp_line
			(start 0.67945 0.3048)
			(end 0.120396 0.3048)
			(stroke
				(width 0.1)
				(type default)
			)
			(layer "F.Fab")
		)
		(fp_line
			(start 0.120396 0.3048)
			(end 0.120396 0.2794)
			(stroke
				(width 0.1)
				(type default)
			)
			(layer "F.Fab")
		)
		(fp_line
			(start -0.12065 0.3048)
			(end -0.67945 0.3048)
			(stroke
				(width 0.1)
				(type default)
			)
			(layer "F.Fab")
		)
		(fp_line
			(start -0.67945 0.3048)
			(end -0.67945 -0.305054)
			(stroke
				(width 0.1)
				(type default)
			)
			(layer "F.Fab")
		)
		(pad "1" smd circle
			(at -0.40005 0 90)
			(size 0 0)
			(layers "F.Cu" "F.Mask" "F.Paste")
			(net "BIC_SEL_FLASH_SW2_R")
		)
		(pad "2" smd circle
			(at 0.40005 0 90)
			(size 0 0)
			(layers "F.Cu" "F.Mask" "F.Paste")
			(net "GND")
		)
	)
	(footprint ""
		(layer "F.Cu")
		(at 288.181542 -158.8516)
		(property "Reference" "R251"
			(at 0 0 0)
			(layer "F.SilkS")
			(hide yes)
			(effects
				(font
					(size 1.27 1.27)
				)
			)
		)
		(property "Value" ""
			(at 0 0 0)
			(layer "F.Fab")
			(effects
				(font
					(size 1.27 1.27)
				)
			)
		)
		(duplicate_pad_numbers_are_jumpers no)
		(fp_line
			(start -0.7874 -0.4064)
			(end 0.7874 -0.4064)
			(stroke
				(width 0.1524)
				(type default)
			)
			(layer "F.SilkS")
		)
		(fp_line
			(start -0.7874 0.4064)
			(end -0.7874 -0.4064)
			(stroke
				(width 0.1524)
				(type default)
			)
			(layer "F.SilkS")
		)
		(fp_line
			(start 0.7874 -0.4064)
			(end 0.7874 0.4064)
			(stroke
				(width 0.1524)
				(type default)
			)
			(layer "F.SilkS")
		)
		(fp_line
			(start 0.7874 0.4064)
			(end -0.7874 0.4064)
			(stroke
				(width 0.1524)
				(type default)
			)
			(layer "F.SilkS")
		)
		(fp_line
			(start -0.67945 -0.305054)
			(end -0.12065 -0.305054)
			(stroke
				(width 0.1)
				(type default)
			)
			(layer "F.Fab")
		)
		(fp_line
			(start -0.67945 0.3048)
			(end -0.67945 -0.305054)
			(stroke
				(width 0.1)
				(type default)
			)
			(layer "F.Fab")
		)
		(fp_line
			(start -0.12065 -0.305054)
			(end -0.12065 -0.2794)
			(stroke
				(width 0.1)
				(type default)
			)
			(layer "F.Fab")
		)
		(fp_line
			(start -0.12065 -0.2794)
			(end 0.12065 -0.2794)
			(stroke
				(width 0.1)
				(type default)
			)
			(layer "F.Fab")
		)
		(fp_line
			(start -0.12065 0.2794)
			(end -0.12065 0.3048)
			(stroke
				(width 0.1)
				(type default)
			)
			(layer "F.Fab")
		)
		(fp_line
			(start -0.12065 0.3048)
			(end -0.67945 0.3048)
			(stroke
				(width 0.1)
				(type default)
			)
			(layer "F.Fab")
		)
		(fp_line
			(start 0.120396 0.2794)
			(end -0.12065 0.2794)
			(stroke
				(width 0.1)
				(type default)
			)
			(layer "F.Fab")
		)
		(fp_line
			(start 0.120396 0.3048)
			(end 0.120396 0.2794)
			(stroke
				(width 0.1)
				(type default)
			)
			(layer "F.Fab")
		)
		(fp_line
			(start 0.12065 -0.3048)
			(end 0.67945 -0.3048)
			(stroke
				(width 0.1)
				(type default)
			)
			(layer "F.Fab")
		)
		(fp_line
			(start 0.12065 -0.2794)
			(end 0.12065 -0.3048)
			(stroke
				(width 0.1)
				(type default)
			)
			(layer "F.Fab")
		)
		(fp_line
			(start 0.67945 -0.3048)
			(end 0.67945 0.3048)
			(stroke
				(width 0.1)
				(type default)
			)
			(layer "F.Fab")
		)
		(fp_line
			(start 0.67945 0.3048)
			(end 0.120396 0.3048)
			(stroke
				(width 0.1)
				(type default)
			)
			(layer "F.Fab")
		)
		(pad "1" smd circle
			(at -0.40005 0)
			(size 0 0)
			(layers "F.Cu" "F.Mask" "F.Paste")
			(net "RST_NIC4_PERST2_R_N")
		)
		(pad "2" smd circle
			(at 0.40005 0)
			(size 0 0)
			(layers "F.Cu" "F.Mask" "F.Paste")
			(net "RST_HP_NIC4_BUF_N")
		)
	)
)
